# T6G (Grand Teton) — schematic netlist excerpt (pin names and nets, part order shuffled) for the footprints in the layout excerpt that follows; sources: Cadence DE-HDL packaged netlist, KiCad conversion of 04192023_DAF0TMB3IC0_F0TG_MB_C_brd_V02_OCP.brd

R6150  Q_RES  1K 1% CHIP  pkg 0402LF  page 84 : A = FAB_BMC_REV_ID1 ; B = GND
R1677  Q_RES  10 1% CHIP  pkg 0402LF  page 88 : A = I3C_SPD_DDRAF_CPU0_SDA ; B = I3C_SPD_DDRC_CPU0_SDA

(kicad_pcb
	(version 20260206)
	(generator "pcbnew")
	(generator_version "10.0")
	(general
		(thickness 1.6)
		(legacy_teardrops no)
	)
	(paper "A4")
	(title_block
		(title "04192023_DAF0TMB3IC0_F0TG_MB_C_brd_V02_OCP.brd")
		(comment 1 "Grand Teton / footprints 5223-5224 of 8354")
	)
	(layers
		(0 "F.Cu" signal "TOP")
		(4 "In1.Cu" signal "GND")
		(6 "In2.Cu" signal "IN1")
		(8 "In3.Cu" signal "GND1")
		(10 "In4.Cu" signal "IN2")
		(12 "In5.Cu" signal "GND2")
		(14 "In6.Cu" signal "IN3")
		(16 "In7.Cu" signal "GND3")
		(18 "In8.Cu" signal "VCC")
		(20 "In9.Cu" signal "VCC1")
		(22 "In10.Cu" signal "GND4")
		(24 "In11.Cu" signal "IN4")
		(26 "In12.Cu" signal "GND5")
		(28 "In13.Cu" signal "IN5")
		(30 "In14.Cu" signal "GND6")
		(32 "In15.Cu" signal "IN6")
		(34 "In16.Cu" signal "GND7")
		(2 "B.Cu" signal "BOTTOM")
		(9 "F.Adhes" user "F.Adhesive")
		(11 "B.Adhes" user "B.Adhesive")
		(13 "F.Paste" user "Package Geometry/Pastemask Top")
		(15 "B.Paste" user "Package Geometry/Pastemask Bottom")
		(5 "F.SilkS" user "Ref Des/Silkscreen Top")
		(7 "B.SilkS" user "Ref Des/Silkscreen Bottom")
		(1 "F.Mask" user "Board Geometry/Soldermask Top")
		(3 "B.Mask" user "Board Geometry/Soldermask Bottom")
		(17 "Dwgs.User" user "User.Drawings")
		(19 "Cmts.User" user "User.Comments")
		(21 "Eco1.User" user "User.Eco1")
		(23 "Eco2.User" user "User.Eco2")
		(25 "Edge.Cuts" user "Board Geometry/Outline")
		(27 "Margin" user)
		(31 "F.CrtYd" user "Package Geometry/Place Bound Top")
		(29 "B.CrtYd" user "Package Geometry/Place Bound Bottom")
		(35 "F.Fab" user "Ref Des/Assembly Top")
		(33 "B.Fab" user "Ref Des/Assembly Bottom")
	)
	(footprint ""
		(layer "B.Cu")
		(at 171.201334 -103.942388 180)
		(property "Reference" "R6150"
			(at 0 0 0)
			(layer "B.SilkS")
			(hide yes)
			(effects
				(font
					(size 1.27 1.27)
				)
				(justify mirror)
			)
		)
		(property "Value" ""
			(at 0 0 0)
			(layer "B.Fab")
			(effects
				(font
					(size 1.27 1.27)
				)
				(justify mirror)
			)
		)
		(duplicate_pad_numbers_are_jumpers no)
		(fp_line
			(start 0.7874 0.4064)
			(end 0.7874 -0.4064)
			(stroke
				(width 0.1524)
				(type default)
			)
			(layer "B.SilkS")
		)
		(fp_line
			(start 0.7874 -0.4064)
			(end -0.7874 -0.4064)
			(stroke
				(width 0.1524)
				(type default)
			)
			(layer "B.SilkS")
		)
		(fp_line
			(start -0.7874 0.4064)
			(end 0.7874 0.4064)
			(stroke
				(width 0.1524)
				(type default)
			)
			(layer "B.SilkS")
		)
		(fp_line
			(start -0.7874 -0.4064)
			(end -0.7874 0.4064)
			(stroke
				(width 0.1524)
				(type default)
			)
			(layer "B.SilkS")
		)
		(fp_line
			(start 0.67945 0.3048)
			(end 0.67945 -0.305054)
			(stroke
				(width 0.1)
				(type default)
			)
			(layer "B.Fab")
		)
		(fp_line
			(start 0.67945 -0.305054)
			(end 0.12065 -0.305054)
			(stroke
				(width 0.1)
				(type default)
			)
			(layer "B.Fab")
		)
		(fp_line
			(start 0.12065 0.3048)
			(end 0.67945 0.3048)
			(stroke
				(width 0.1)
				(type default)
			)
			(layer "B.Fab")
		)
		(fp_line
			(start 0.12065 0.2794)
			(end 0.12065 0.3048)
			(stroke
				(width 0.1)
				(type default)
			)
			(layer "B.Fab")
		)
		(fp_line
			(start 0.12065 -0.2794)
			(end -0.12065 -0.2794)
			(stroke
				(width 0.1)
				(type default)
			)
			(layer "B.Fab")
		)
		(fp_line
			(start 0.12065 -0.305054)
			(end 0.12065 -0.2794)
			(stroke
				(width 0.1)
				(type default)
			)
			(layer "B.Fab")
		)
		(fp_line
			(start -0.120396 0.3048)
			(end -0.120396 0.2794)
			(stroke
				(width 0.1)
				(type default)
			)
			(layer "B.Fab")
		)
		(fp_line
			(start -0.120396 0.2794)
			(end 0.12065 0.2794)
			(stroke
				(width 0.1)
				(type default)
			)
			(layer "B.Fab")
		)
		(fp_line
			(start -0.12065 -0.2794)
			(end -0.12065 -0.3048)
			(stroke
				(width 0.1)
				(type default)
			)
			(layer "B.Fab")
		)
		(fp_line
			(start -0.12065 -0.3048)
			(end -0.67945 -0.3048)
			(stroke
				(width 0.1)
				(type default)
			)
			(layer "B.Fab")
		)
		(fp_line
			(start -0.67945 0.3048)
			(end -0.120396 0.3048)
			(stroke
				(width 0.1)
				(type default)
			)
			(layer "B.Fab")
		)
		(fp_line
			(start -0.67945 -0.3048)
			(end -0.67945 0.3048)
			(stroke
				(width 0.1)
				(type default)
			)
			(layer "B.Fab")
		)
		(pad "1" smd circle
			(at 0.40005 0)
			(size 0 0)
			(layers "B.Cu" "B.Mask" "B.Paste")
			(net "FAB_BMC_REV_ID1")
		)
		(pad "2" smd circle
			(at -0.40005 0)
			(size 0 0)
			(layers "B.Cu" "B.Mask" "B.Paste")
			(net "GND")
		)
	)
	(footprint ""
		(layer "B.Cu")
		(at 291.52469 -195.859146 180)
		(property "Reference" "R1677"
			(at 0 0 0)
			(layer "B.SilkS")
			(hide yes)
			(effects
				(font
					(size 1.27 1.27)
				)
				(justify mirror)
			)
		)
		(property "Value" ""
			(at 0 0 0)
			(layer "B.Fab")
			(effects
				(font
					(size 1.27 1.27)
				)
				(justify mirror)
			)
		)
		(duplicate_pad_numbers_are_jumpers no)
		(fp_line
			(start 0.7874 0.4064)
			(end 0.7874 -0.4064)
			(stroke
				(width 0.1524)
				(type default)
			)
			(layer "B.SilkS")
		)
		(fp_line
			(start 0.7874 -0.4064)
			(end -0.7874 -0.4064)
			(stroke
				(width 0.1524)
				(type default)
			)
			(layer "B.SilkS")
		)
		(fp_line
			(start -0.7874 0.4064)
			(end 0.7874 0.4064)
			(stroke
				(width 0.1524)
				(type default)
			)
			(layer "B.SilkS")
		)
		(fp_line
			(start -0.7874 -0.4064)
			(end -0.7874 0.4064)
			(stroke
				(width 0.1524)
				(type default)
			)
			(layer "B.SilkS")
		)
		(fp_line
			(start 0.67945 0.3048)
			(end 0.67945 -0.305054)
			(stroke
				(width 0.1)
				(type default)
			)
			(layer "B.Fab")
		)
		(fp_line
			(start 0.67945 -0.305054)
			(end 0.12065 -0.305054)
			(stroke
				(width 0.1)
				(type default)
			)
			(layer "B.Fab")
		)
		(fp_line
			(start 0.12065 0.3048)
			(end 0.67945 0.3048)
			(stroke
				(width 0.1)
				(type default)
			)
			(layer "B.Fab")
		)
		(fp_line
			(start 0.12065 0.2794)
			(end 0.12065 0.3048)
			(stroke
				(width 0.1)
				(type default)
			)
			(layer "B.Fab")
		)
		(fp_line
			(start 0.12065 -0.2794)
			(end -0.12065 -0.2794)
			(stroke
				(width 0.1)
				(type default)
			)
			(layer "B.Fab")
		)
		(fp_line
			(start 0.12065 -0.305054)
			(end 0.12065 -0.2794)
			(stroke
				(width 0.1)
				(type default)
			)
			(layer "B.Fab")
		)
		(fp_line
			(start -0.120396 0.3048)
			(end -0.120396 0.2794)
			(stroke
				(width 0.1)
				(type default)
			)
			(layer "B.Fab")
		)
		(fp_line
			(start -0.120396 0.2794)
			(end 0.12065 0.2794)
			(stroke
				(width 0.1)
				(type default)
			)
			(layer "B.Fab")
		)
		(fp_line
			(start -0.12065 -0.2794)
			(end -0.12065 -0.3048)
			(stroke
				(width 0.1)
				(type default)
			)
			(layer "B.Fab")
		)
		(fp_line
			(start -0.12065 -0.3048)
			(end -0.67945 -0.3048)
			(stroke
				(width 0.1)
				(type default)
			)
			(layer "B.Fab")
		)
		(fp_line
			(start -0.67945 0.3048)
			(end -0.120396 0.3048)
			(stroke
				(width 0.1)
				(type default)
			)
			(layer "B.Fab")
		)
		(fp_line
			(start -0.67945 -0.3048)
			(end -0.67945 0.3048)
			(stroke
				(width 0.1)
				(type default)
			)
			(layer "B.Fab")
		)
		(pad "1" smd circle
			(at 0.40005 0)
			(size 0 0)
			(layers "B.Cu" "B.Mask" "B.Paste")
			(net "I3C_SPD_DDRAF_CPU0_SDA")
		)
		(pad "2" smd circle
			(at -0.40005 0)
			(size 0 0)
			(layers "B.Cu" "B.Mask" "B.Paste")
			(net "I3C_SPD_DDRC_CPU0_SDA")
		)
	)
)
